(kicad_pcb
	(version 20260206)
	(generator "pcbnew")
	(generator_version "10.0")
	(general
		(thickness 1.6)
		(legacy_teardrops no)
	)
	(paper "A4")
	(title_block
		(title "03242023_DA0F0TMBIJ0_F0T_Motherboard_J_brd_V01_OCP.brd")
		(comment 1 "Grand Teton / footprint 1585 of 6105 (U4), pads 228-339 of 749")
	)
	(layers
		(0 "F.Cu" signal "TOP")
		(4 "In1.Cu" signal "GND")
		(6 "In2.Cu" signal "IN1")
		(8 "In3.Cu" signal "GND1")
		(10 "In4.Cu" signal "IN2")
		(12 "In5.Cu" signal "GND2")
		(14 "In6.Cu" signal "IN3")
		(16 "In7.Cu" signal "GND3")
		(18 "In8.Cu" signal "VCC")
		(20 "In9.Cu" signal "VCC1")
		(22 "In10.Cu" signal "GND4")
		(24 "In11.Cu" signal "IN4")
		(26 "In12.Cu" signal "GND5")
		(28 "In13.Cu" signal "IN5")
		(30 "In14.Cu" signal "GND6")
		(32 "In15.Cu" signal "IN6")
		(34 "In16.Cu" signal "GND7")
		(2 "B.Cu" signal "BOTTOM")
		(9 "F.Adhes" user "F.Adhesive")
		(11 "B.Adhes" user "B.Adhesive")
		(13 "F.Paste" user "Package Geometry/Pastemask Top")
		(15 "B.Paste" user "Package Geometry/Pastemask Bottom")
		(5 "F.SilkS" user "Ref Des/Silkscreen Top")
		(7 "B.SilkS" user "Ref Des/Silkscreen Bottom")
		(1 "F.Mask" user "Board Geometry/Soldermask Top")
		(3 "B.Mask" user "Board Geometry/Soldermask Bottom")
		(17 "Dwgs.User" user "User.Drawings")
		(19 "Cmts.User" user "User.Comments")
		(21 "Eco1.User" user "User.Eco1")
		(23 "Eco2.User" user "User.Eco2")
		(25 "Edge.Cuts" user "Board Geometry/Outline")
		(27 "Margin" user)
		(31 "F.CrtYd" user "Package Geometry/Place Bound Top")
		(29 "B.CrtYd" user "Package Geometry/Place Bound Bottom")
		(35 "F.Fab" user "Ref Des/Assembly Top")
		(33 "B.Fab" user "Ref Des/Assembly Bottom")
	)
	(footprint ""
		(layer "F.Cu")
		(at 336.899758 -48.450246)
		(property "Reference" "U4"
			(at -13.479018 -11.486896 0)
			(unlocked yes)
			(layer "F.SilkS")
			(effects
				(font
					(size 0.7874 0.5842)
					(thickness 0.1524)
				)
				(justify left)
			)
		)
		(property "Value" ""
			(at 0 0 0)
			(layer "F.Fab")
			(effects
				(font
					(size 1.27 1.27)
				)
			)
		)
		(duplicate_pad_numbers_are_jumpers no)
		(pad "AR2" smd circle
			(at -9.899904 5.002276 180)
			(size 0.3048 0.3048)
			(layers "F.Cu" "F.Mask" "F.Paste")
			(net "PD_PCH_GPPC_C9")
		)
		(pad "AR4" smd circle
			(at -9.069832 5.002276 180)
			(size 0.3048 0.3048)
			(layers "F.Cu" "F.Mask" "F.Paste")
			(net "IRQ_SML1_PMBUS_ALERT_N")
		)
		(pad "AR7" smd circle
			(at -7.733792 5.1689 180)
			(size 0.381 0.381)
			(layers "F.Cu" "F.Mask" "F.Paste")
			(net "PD_SUSCLK")
		)
		(pad "AR10" smd circle
			(at -6.105398 5.1689 180)
			(size 0.381 0.381)
			(layers "F.Cu" "F.Mask" "F.Paste")
			(net "FM_BMC_PWRBTN_N")
		)
		(pad "AR13" smd circle
			(at -4.477512 5.1689 180)
			(size 0.381 0.381)
			(layers "F.Cu" "F.Mask" "F.Paste")
			(net "FM_EUP_LOT6_N")
		)
		(pad "AR16" smd circle
			(at -2.849118 5.1689 180)
			(size 0.381 0.381)
			(layers "F.Cu" "F.Mask" "F.Paste")
			(net "FM_XTAL_INPUT_FREQUENCY_1_MGPIO")
		)
		(pad "AR20" smd circle
			(at -1.220978 5.1689 180)
			(size 0.381 0.381)
			(layers "F.Cu" "F.Mask" "F.Paste")
			(net "GND")
		)
		(pad "AR23" smd circle
			(at 0.406908 5.1689 180)
			(size 0.381 0.381)
			(layers "F.Cu" "F.Mask" "F.Paste")
			(net "P1V05_PCH_AUX")
		)
		(pad "AR26" smd circle
			(at 2.035302 5.1689 180)
			(size 0.381 0.381)
			(layers "F.Cu" "F.Mask" "F.Paste")
			(net "P1V05_PCH_AUX")
		)
		(pad "AR29" smd circle
			(at 3.663188 5.1689 180)
			(size 0.381 0.381)
			(layers "F.Cu" "F.Mask" "F.Paste")
			(net "PCH_PCIEUP_RCOMPP")
		)
		(pad "AR32" smd circle
			(at 5.291582 5.1689 180)
			(size 0.381 0.381)
			(layers "F.Cu" "F.Mask" "F.Paste")
			(net "GND")
		)
		(pad "AR36" smd circle
			(at 6.919722 5.1689 180)
			(size 0.381 0.381)
			(layers "F.Cu" "F.Mask" "F.Paste")
			(net "P3E_PCH_M2_TX_DN<2>")
		)
		(pad "AR40" smd circle
			(at 9.069832 5.002276 180)
			(size 0.3048 0.3048)
			(layers "F.Cu" "F.Mask" "F.Paste")
			(net "USB2_0_DP")
		)
		(pad "AR42" smd circle
			(at 9.899904 5.002276 180)
			(size 0.3048 0.3048)
			(layers "F.Cu" "F.Mask" "F.Paste")
			(net "USB2_0_DN")
		)
		(pad "AT1" smd oval
			(at -10.31494 5.502656 270)
			(size 0.254 0.3302)
			(layers "F.Cu" "F.Mask" "F.Paste")
			(net "PU_SMB_PCH_PLD_3V3AUX_SDA")
		)
		(pad "AT3" smd circle
			(at -9.484868 5.502656 180)
			(size 0.3048 0.3048)
			(layers "F.Cu" "F.Mask" "F.Paste")
			(net "PD_PCH_GPPC_C5")
		)
		(pad "AT5" smd circle
			(at -8.654796 5.502656 180)
			(size 0.3048 0.3048)
			(layers "F.Cu" "F.Mask" "F.Paste")
			(net "GND")
		)
		(pad "AT8" smd circle
			(at -6.919722 5.6388 180)
			(size 0.381 0.381)
			(layers "F.Cu" "F.Mask" "F.Paste")
			(net "GND")
		)
		(pad "AT11" smd circle
			(at -5.291582 5.6388 180)
			(size 0.381 0.381)
			(layers "F.Cu" "F.Mask" "F.Paste")
			(net "GND")
		)
		(pad "AT15" smd circle
			(at -3.663188 5.6388 180)
			(size 0.381 0.381)
			(layers "F.Cu" "F.Mask" "F.Paste")
			(net "GND")
		)
		(pad "AT18" smd circle
			(at -2.035302 5.6388 180)
			(size 0.381 0.381)
			(layers "F.Cu" "F.Mask" "F.Paste")
			(net "FM_PCH_CONSENT_STRAP_N")
		)
		(pad "AT21" smd circle
			(at -0.406908 5.6388 180)
			(size 0.381 0.381)
			(layers "F.Cu" "F.Mask" "F.Paste")
			(net "GND")
		)
		(pad "AT24" smd circle
			(at 1.220978 5.6388 180)
			(size 0.381 0.381)
			(layers "F.Cu" "F.Mask" "F.Paste")
			(net "GND")
		)
		(pad "AT28" smd circle
			(at 2.849118 5.6388 180)
			(size 0.381 0.381)
			(layers "F.Cu" "F.Mask" "F.Paste")
			(net "GND")
		)
		(pad "AT31" smd circle
			(at 4.477512 5.6388 180)
			(size 0.381 0.381)
			(layers "F.Cu" "F.Mask" "F.Paste")
			(net "GND")
		)
		(pad "AT34" smd circle
			(at 6.105398 5.6388 180)
			(size 0.381 0.381)
			(layers "F.Cu" "F.Mask" "F.Paste")
			(net "GND")
		)
		(pad "AT37" smd circle
			(at 7.733792 5.6388 180)
			(size 0.381 0.381)
			(layers "F.Cu" "F.Mask" "F.Paste")
			(net "P3E_PCH_M2_TX_DP<2>")
		)
		(pad "AT39" smd circle
			(at 8.654796 5.502656 180)
			(size 0.3048 0.3048)
			(layers "F.Cu" "F.Mask" "F.Paste")
			(net "GND")
		)
		(pad "AT41" smd circle
			(at 9.484868 5.502656 180)
			(size 0.3048 0.3048)
			(layers "F.Cu" "F.Mask" "F.Paste")
			(net "TP_USB2_2_DP")
		)
		(pad "AT43" smd oval
			(at 10.31494 5.502656 270)
			(size 0.254 0.3302)
			(layers "F.Cu" "F.Mask" "F.Paste")
			(net "TP_USB2_2_DN")
		)
		(pad "AU2" smd circle
			(at -9.899904 6.002782 180)
			(size 0.3048 0.3048)
			(layers "F.Cu" "F.Mask" "F.Paste")
			(net "IRQ_SML0_ALERT_N")
		)
		(pad "AU4" smd circle
			(at -9.069832 6.002782 180)
			(size 0.3048 0.3048)
			(layers "F.Cu" "F.Mask" "F.Paste")
			(net "SMB_SML0B_3V3AUX_SDA")
		)
		(pad "AU7" smd circle
			(at -7.733792 6.1087 180)
			(size 0.381 0.381)
			(layers "F.Cu" "F.Mask" "F.Paste")
			(net "PU_LAN_WAKE_N")
		)
		(pad "AU10" smd circle
			(at -6.105398 6.1087 180)
			(size 0.381 0.381)
			(layers "F.Cu" "F.Mask" "F.Paste")
			(net "FM_PCH_SKIP_RTC_CLOCK")
		)
		(pad "AU13" smd circle
			(at -4.477512 6.1087 180)
			(size 0.381 0.381)
			(layers "F.Cu" "F.Mask" "F.Paste")
			(net "FM_SPI_3V3_1V8_VOLTAGE")
		)
		(pad "AU16" smd circle
			(at -2.849118 6.1087 180)
			(size 0.381 0.381)
			(layers "F.Cu" "F.Mask" "F.Paste")
			(net "FM_PCH_SPKR")
		)
		(pad "AU20" smd circle
			(at -1.220978 6.1087 180)
			(size 0.381 0.381)
			(layers "F.Cu" "F.Mask" "F.Paste")
			(net "GND")
		)
		(pad "AU23" smd circle
			(at 0.406908 6.1087 180)
			(size 0.381 0.381)
			(layers "F.Cu" "F.Mask" "F.Paste")
			(net "GND")
		)
		(pad "AU26" smd circle
			(at 2.035302 6.1087 180)
			(size 0.381 0.381)
			(layers "F.Cu" "F.Mask" "F.Paste")
			(net "GND")
		)
		(pad "AU29" smd circle
			(at 3.663188 6.1087 180)
			(size 0.381 0.381)
			(layers "F.Cu" "F.Mask" "F.Paste")
			(net "GND")
		)
		(pad "AU32" smd circle
			(at 5.291582 6.1087 180)
			(size 0.381 0.381)
			(layers "F.Cu" "F.Mask" "F.Paste")
			(net "GND")
		)
		(pad "AU36" smd circle
			(at 6.919722 6.1087 180)
			(size 0.381 0.381)
			(layers "F.Cu" "F.Mask" "F.Paste")
			(net "GND")
		)
		(pad "AU40" smd circle
			(at 9.069832 6.002782 180)
			(size 0.3048 0.3048)
			(layers "F.Cu" "F.Mask" "F.Paste")
			(net "TP_USB2_4_DP")
		)
		(pad "AU42" smd circle
			(at 9.899904 6.002782 180)
			(size 0.3048 0.3048)
			(layers "F.Cu" "F.Mask" "F.Paste")
			(net "TP_USB2_4_DN")
		)
		(pad "AV1" smd oval
			(at -10.31494 6.503162 270)
			(size 0.254 0.3302)
			(layers "F.Cu" "F.Mask" "F.Paste")
			(net "PU_SMB_SML4_3V3AUX_PCH_SDA")
		)
		(pad "AV3" smd circle
			(at -9.484868 6.503162 180)
			(size 0.3048 0.3048)
			(layers "F.Cu" "F.Mask" "F.Paste")
			(net "FM_PMBUS_ALERT_B_EN")
		)
		(pad "AV5" smd circle
			(at -8.654796 6.503162 180)
			(size 0.3048 0.3048)
			(layers "F.Cu" "F.Mask" "F.Paste")
			(net "GND")
		)
		(pad "AV8" smd circle
			(at -6.919722 6.5786 180)
			(size 0.381 0.381)
			(layers "F.Cu" "F.Mask" "F.Paste")
			(net "GND")
		)
		(pad "AV11" smd circle
			(at -5.291582 6.5786 180)
			(size 0.381 0.381)
			(layers "F.Cu" "F.Mask" "F.Paste")
			(net "FM_ADR_MODE0")
		)
		(pad "AV15" smd circle
			(at -3.663188 6.5786 180)
			(size 0.381 0.381)
			(layers "F.Cu" "F.Mask" "F.Paste")
			(net "SPI_PCH_IO2")
		)
		(pad "AV18" smd circle
			(at -2.035302 6.5786 180)
			(size 0.381 0.381)
			(layers "F.Cu" "F.Mask" "F.Paste")
			(net "IRQ_SMI_ACTIVE_N")
		)
		(pad "AV21" smd circle
			(at -0.406908 6.5786 180)
			(size 0.381 0.381)
			(layers "F.Cu" "F.Mask" "F.Paste")
			(net "NC_PCH_RSVD<4>")
		)
		(pad "AV24" smd circle
			(at 1.220978 6.5786 180)
			(size 0.381 0.381)
			(layers "F.Cu" "F.Mask" "F.Paste")
			(net "TP_EDSFF1A_TYPE_ID")
		)
		(pad "AV28" smd circle
			(at 2.849118 6.5786 180)
			(size 0.381 0.381)
			(layers "F.Cu" "F.Mask" "F.Paste")
			(net "TP_EDSFF1B_TYPE_ID")
		)
		(pad "AV31" smd circle
			(at 4.477512 6.5786 180)
			(size 0.381 0.381)
			(layers "F.Cu" "F.Mask" "F.Paste")
			(net "PD_PCH_GPP_E_10")
		)
		(pad "AV34" smd circle
			(at 6.105398 6.5786 180)
			(size 0.381 0.381)
			(layers "F.Cu" "F.Mask" "F.Paste")
			(net "PD_PCH_GPP_E_11")
		)
		(pad "AV37" smd circle
			(at 7.733792 6.5786 180)
			(size 0.381 0.381)
			(layers "F.Cu" "F.Mask" "F.Paste")
			(net "GND")
		)
		(pad "AV39" smd circle
			(at 8.654796 6.503162 180)
			(size 0.3048 0.3048)
			(layers "F.Cu" "F.Mask" "F.Paste")
			(net "GND")
		)
		(pad "AV41" smd circle
			(at 9.484868 6.503162 180)
			(size 0.3048 0.3048)
			(layers "F.Cu" "F.Mask" "F.Paste")
			(net "TP_USB2_6_DP")
		)
		(pad "AV43" smd oval
			(at 10.31494 6.503162 270)
			(size 0.254 0.3302)
			(layers "F.Cu" "F.Mask" "F.Paste")
			(net "TP_USB2_6_DN")
		)
		(pad "AW2" smd circle
			(at -9.899904 7.003288 180)
			(size 0.3048 0.3048)
			(layers "F.Cu" "F.Mask" "F.Paste")
			(net "FM_THROTTLE_N")
		)
		(pad "AW4" smd circle
			(at -9.069832 7.003288 180)
			(size 0.3048 0.3048)
			(layers "F.Cu" "F.Mask" "F.Paste")
			(net "SMB_SML1_PMBUS_3V3AUX_PCH_SDA_1")
		)
		(pad "AW7" smd circle
			(at -7.733792 7.0485 180)
			(size 0.381 0.381)
			(layers "F.Cu" "F.Mask" "F.Paste")
			(net "GND")
		)
		(pad "AW10" smd circle
			(at -6.105398 7.0485 180)
			(size 0.381 0.381)
			(layers "F.Cu" "F.Mask" "F.Paste")
			(net "FM_JTAG_ODT_DISABLE")
		)
		(pad "AW13" smd circle
			(at -4.477512 7.0485 180)
			(size 0.381 0.381)
			(layers "F.Cu" "F.Mask" "F.Paste")
			(net "SPI_PCH_CS0_R_N")
		)
		(pad "AW16" smd circle
			(at -2.849118 7.0485 180)
			(size 0.381 0.381)
			(layers "F.Cu" "F.Mask" "F.Paste")
			(net "SPI_PCH_IO1")
		)
		(pad "AW20" smd circle
			(at -1.220978 7.0485 180)
			(size 0.381 0.381)
			(layers "F.Cu" "F.Mask" "F.Paste")
			(net "FM_ME_AUTHN_FAIL")
		)
		(pad "AW23" smd circle
			(at 0.406908 7.0485 180)
			(size 0.381 0.381)
			(layers "F.Cu" "F.Mask" "F.Paste")
			(net "TP_PCH_GPP_E_2")
		)
		(pad "AW26" smd circle
			(at 2.035302 7.0485 180)
			(size 0.381 0.381)
			(layers "F.Cu" "F.Mask" "F.Paste")
			(net "NC_PCH_RSVD<3>")
		)
		(pad "AW29" smd circle
			(at 3.663188 7.0485 180)
			(size 0.381 0.381)
			(layers "F.Cu" "F.Mask" "F.Paste")
			(net "FM_ME_BT_DONE")
		)
		(pad "AW32" smd circle
			(at 5.291582 7.0485 180)
			(size 0.381 0.381)
			(layers "F.Cu" "F.Mask" "F.Paste")
			(net "FM_M2_SSD0_E7_PEDET")
		)
		(pad "AW36" smd circle
			(at 6.919722 7.0485 180)
			(size 0.381 0.381)
			(layers "F.Cu" "F.Mask" "F.Paste")
			(net "PD_PCH_GPP_E_8")
		)
		(pad "AW40" smd circle
			(at 9.069832 7.003288 180)
			(size 0.3048 0.3048)
			(layers "F.Cu" "F.Mask" "F.Paste")
			(net "USB2_8_DP")
		)
		(pad "AW42" smd circle
			(at 9.899904 7.003288 180)
			(size 0.3048 0.3048)
			(layers "F.Cu" "F.Mask" "F.Paste")
			(net "USB2_8_DN")
		)
		(pad "AY1" smd oval
			(at -10.31494 7.503668 270)
			(size 0.254 0.3302)
			(layers "F.Cu" "F.Mask" "F.Paste")
			(net "PU_SMB_SML3_3V3AUX_PCH_SDA")
		)
		(pad "AY3" smd circle
			(at -9.484868 7.503668 180)
			(size 0.3048 0.3048)
			(layers "F.Cu" "F.Mask" "F.Paste")
			(net "GND")
		)
		(pad "AY5" smd circle
			(at -8.654796 7.503668 180)
			(size 0.3048 0.3048)
			(layers "F.Cu" "F.Mask" "F.Paste")
			(net "GND")
		)
		(pad "AY8" smd circle
			(at -6.919722 7.5184 180)
			(size 0.381 0.381)
			(layers "F.Cu" "F.Mask" "F.Paste")
			(net "GND")
		)
		(pad "AY11" smd circle
			(at -5.291582 7.5184 180)
			(size 0.381 0.381)
			(layers "F.Cu" "F.Mask" "F.Paste")
			(net "GND")
		)
		(pad "AY15" smd circle
			(at -3.663188 7.5184 180)
			(size 0.381 0.381)
			(layers "F.Cu" "F.Mask" "F.Paste")
			(net "GND")
		)
		(pad "AY18" smd circle
			(at -2.035302 7.5184 180)
			(size 0.381 0.381)
			(layers "F.Cu" "F.Mask" "F.Paste")
			(net "GND")
		)
		(pad "AY21" smd circle
			(at -0.406908 7.5184 180)
			(size 0.381 0.381)
			(layers "F.Cu" "F.Mask" "F.Paste")
			(net "GND")
		)
		(pad "AY24" smd circle
			(at 1.220978 7.5184 180)
			(size 0.381 0.381)
			(layers "F.Cu" "F.Mask" "F.Paste")
			(net "GND")
		)
		(pad "AY28" smd circle
			(at 2.849118 7.5184 180)
			(size 0.381 0.381)
			(layers "F.Cu" "F.Mask" "F.Paste")
			(net "GND")
		)
		(pad "AY31" smd circle
			(at 4.477512 7.5184 180)
			(size 0.381 0.381)
			(layers "F.Cu" "F.Mask" "F.Paste")
			(net "GND")
		)
		(pad "AY34" smd circle
			(at 6.105398 7.5184 180)
			(size 0.381 0.381)
			(layers "F.Cu" "F.Mask" "F.Paste")
			(net "GND")
		)
		(pad "AY37" smd circle
			(at 7.733792 7.5184 180)
			(size 0.381 0.381)
			(layers "F.Cu" "F.Mask" "F.Paste")
			(net "GND")
		)
		(pad "AY39" smd circle
			(at 8.654796 7.503668 180)
			(size 0.3048 0.3048)
			(layers "F.Cu" "F.Mask" "F.Paste")
			(net "GND")
		)
		(pad "AY41" smd circle
			(at 9.484868 7.503668 180)
			(size 0.3048 0.3048)
			(layers "F.Cu" "F.Mask" "F.Paste")
			(net "TP_USB2_10_DP")
		)
		(pad "AY43" smd oval
			(at 10.31494 7.503668 270)
			(size 0.254 0.3302)
			(layers "F.Cu" "F.Mask" "F.Paste")
			(net "TP_USB2_10_DN")
		)
		(pad "B5" smd circle
			(at -8.504174 -10.40003 180)
			(size 0.3048 0.3048)
			(layers "F.Cu" "F.Mask" "F.Paste")
			(net "TP_CLK_100M_PCH_15_DN")
		)
		(pad "B7" smd circle
			(at -7.503668 -10.40003 180)
			(size 0.3048 0.3048)
			(layers "F.Cu" "F.Mask" "F.Paste")
			(net "TP_CLK_100M_PCH_14_DN")
		)
		(pad "B9" smd circle
			(at -6.503162 -10.40003 180)
			(size 0.3048 0.3048)
			(layers "F.Cu" "F.Mask" "F.Paste")
			(net "GND")
		)
		(pad "B11" smd circle
			(at -5.502656 -10.40003 180)
			(size 0.3048 0.3048)
			(layers "F.Cu" "F.Mask" "F.Paste")
			(net "CLK_100M_BMC_P3E_DN")
		)
		(pad "B13" smd circle
			(at -4.50215 -10.40003 180)
			(size 0.3048 0.3048)
			(layers "F.Cu" "F.Mask" "F.Paste")
			(net "GND")
		)
		(pad "B15" smd circle
			(at -3.501644 -10.40003 180)
			(size 0.3048 0.3048)
			(layers "F.Cu" "F.Mask" "F.Paste")
			(net "TP_CLK_100M_PCH_9_DN")
		)
		(pad "B17" smd circle
			(at -2.501138 -10.40003 180)
			(size 0.3048 0.3048)
			(layers "F.Cu" "F.Mask" "F.Paste")
			(net "CLK_100M_E1S_0_R_DN")
		)
		(pad "B19" smd circle
			(at -1.500632 -10.40003 180)
			(size 0.3048 0.3048)
			(layers "F.Cu" "F.Mask" "F.Paste")
			(net "TP_CLK_100M_PCH_4_DN")
		)
		(pad "B21" smd circle
			(at -0.500126 -10.40003 180)
			(size 0.3048 0.3048)
			(layers "F.Cu" "F.Mask" "F.Paste")
			(net "CLK_100M_CK440_PCH_EXTCLK_DP")
		)
		(pad "B23" smd circle
			(at 0.500126 -10.40003 180)
			(size 0.3048 0.3048)
			(layers "F.Cu" "F.Mask" "F.Paste")
			(net "XTAL_PCH_25M_IN")
		)
		(pad "B25" smd circle
			(at 1.500632 -10.40003 180)
			(size 0.3048 0.3048)
			(layers "F.Cu" "F.Mask" "F.Paste")
			(net "CLK_25M_PCH_REF_NS_DP")
		)
		(pad "B27" smd circle
			(at 2.501138 -10.40003 180)
			(size 0.3048 0.3048)
			(layers "F.Cu" "F.Mask" "F.Paste")
			(net "CLK_25M_PCH_CPU0_DP")
		)
		(pad "B29" smd circle
			(at 3.501644 -10.40003 180)
			(size 0.3048 0.3048)
			(layers "F.Cu" "F.Mask" "F.Paste")
			(net "GND")
		)
		(pad "B31" smd circle
			(at 4.50215 -10.40003 180)
			(size 0.3048 0.3048)
			(layers "F.Cu" "F.Mask" "F.Paste")
			(net "DMI_CPU0_PCH_TX_C_DN<1>")
		)
		(pad "B33" smd circle
			(at 5.502656 -10.40003 180)
			(size 0.3048 0.3048)
			(layers "F.Cu" "F.Mask" "F.Paste")
			(net "DMI_CPU0_PCH_TX_C_DN<3>")
		)
		(pad "B35" smd circle
			(at 6.503162 -10.40003 180)
			(size 0.3048 0.3048)
			(layers "F.Cu" "F.Mask" "F.Paste")
			(net "DMI_CPU0_PCH_TX_C_DN<5>")
		)
		(pad "B37" smd circle
			(at 7.503668 -10.40003 180)
			(size 0.3048 0.3048)
			(layers "F.Cu" "F.Mask" "F.Paste")
			(net "DMI_CPU0_PCH_TX_C_DN<7>")
		)
		(pad "B39" smd circle
			(at 8.504174 -10.40003 180)
			(size 0.3048 0.3048)
			(layers "F.Cu" "F.Mask" "F.Paste")
			(net "GND")
		)
		(pad "BA2" smd circle
			(at -9.899904 8.003794 180)
			(size 0.3048 0.3048)
			(layers "F.Cu" "F.Mask" "F.Paste")
			(net "PU_SMB_SML4_3V3AUX_PCH_SCL")
		)
		(pad "BA4" smd circle
			(at -9.069832 8.003794 180)
			(size 0.3048 0.3048)
			(layers "F.Cu" "F.Mask" "F.Paste")
			(net "SMB_SML0_3V3AUX_PCH_SDA")
		)
		(pad "BA7" smd circle
			(at -7.733792 7.9883 180)
			(size 0.381 0.381)
			(layers "F.Cu" "F.Mask" "F.Paste")
			(net "FM_SUSACK_N")
		)
		(pad "BA10" smd circle
			(at -6.105398 7.9883 180)
			(size 0.381 0.381)
			(layers "F.Cu" "F.Mask" "F.Paste")
			(net "TP_SPI_PCH_CS1_R_N")
		)
	)
)
